# T6G (Grand Teton) — schematic netlist excerpt (pin names and nets, part order shuffled) for the footprints in the layout excerpt that follows; sources: Cadence DE-HDL packaged netlist, KiCad conversion of 04192023_DAF0TMB3IC0_F0TG_MB_C_brd_V02_OCP.brd

PC152  Q_CAP  22UF 16V 20% X6S  pkg C0805  page 226 : A = SW_P12V_AUX_PVDD18_S5_P1_FLT ; B = GND
R6146  Q_RES  1K 1% CHIP  pkg 0402LF  page 84 : A = P1V8_AUX ; B = FAB_BMC_REV_ID2
C882  Q_CAP_DIFFBUS  DIFF BUS_0.22UF 6.3V 20% X6S  pkg C0201  page 64 : \1\ = P5E_CPU0_P3_TX_C_DN<9> ; \2\ = P5E_CPU0_P3_TX_DN<9>

(kicad_pcb
	(version 20260206)
	(generator "pcbnew")
	(generator_version "10.0")
	(general
		(thickness 1.6)
		(legacy_teardrops no)
	)
	(paper "A4")
	(title_block
		(title "04192023_DAF0TMB3IC0_F0TG_MB_C_brd_V02_OCP.brd")
		(comment 1 "Grand Teton / footprints 1612-1614 of 8354")
	)
	(layers
		(0 "F.Cu" signal "TOP")
		(4 "In1.Cu" signal "GND")
		(6 "In2.Cu" signal "IN1")
		(8 "In3.Cu" signal "GND1")
		(10 "In4.Cu" signal "IN2")
		(12 "In5.Cu" signal "GND2")
		(14 "In6.Cu" signal "IN3")
		(16 "In7.Cu" signal "GND3")
		(18 "In8.Cu" signal "VCC")
		(20 "In9.Cu" signal "VCC1")
		(22 "In10.Cu" signal "GND4")
		(24 "In11.Cu" signal "IN4")
		(26 "In12.Cu" signal "GND5")
		(28 "In13.Cu" signal "IN5")
		(30 "In14.Cu" signal "GND6")
		(32 "In15.Cu" signal "IN6")
		(34 "In16.Cu" signal "GND7")
		(2 "B.Cu" signal "BOTTOM")
		(9 "F.Adhes" user "F.Adhesive")
		(11 "B.Adhes" user "B.Adhesive")
		(13 "F.Paste" user "Package Geometry/Pastemask Top")
		(15 "B.Paste" user "Package Geometry/Pastemask Bottom")
		(5 "F.SilkS" user "Ref Des/Silkscreen Top")
		(7 "B.SilkS" user "Ref Des/Silkscreen Bottom")
		(1 "F.Mask" user "Board Geometry/Soldermask Top")
		(3 "B.Mask" user "Board Geometry/Soldermask Bottom")
		(17 "Dwgs.User" user "User.Drawings")
		(19 "Cmts.User" user "User.Comments")
		(21 "Eco1.User" user "User.Eco1")
		(23 "Eco2.User" user "User.Eco2")
		(25 "Edge.Cuts" user "Board Geometry/Outline")
		(27 "Margin" user)
		(31 "F.CrtYd" user "Package Geometry/Place Bound Top")
		(29 "B.CrtYd" user "Package Geometry/Place Bound Bottom")
		(35 "F.Fab" user "Ref Des/Assembly Top")
		(33 "B.Fab" user "Ref Des/Assembly Bottom")
	)
	(footprint ""
		(layer "F.Cu")
		(at 179.71643 -92.664534 90)
		(property "Reference" "R6146"
			(at 0 0 90)
			(layer "F.SilkS")
			(hide yes)
			(effects
				(font
					(size 1.27 1.27)
				)
			)
		)
		(property "Value" ""
			(at 0 0 90)
			(layer "F.Fab")
			(effects
				(font
					(size 1.27 1.27)
				)
			)
		)
		(duplicate_pad_numbers_are_jumpers no)
		(fp_line
			(start 0.7874 -0.4064)
			(end 0.7874 0.4064)
			(stroke
				(width 0.1524)
				(type default)
			)
			(layer "F.SilkS")
		)
		(fp_line
			(start -0.7874 -0.4064)
			(end 0.7874 -0.4064)
			(stroke
				(width 0.1524)
				(type default)
			)
			(layer "F.SilkS")
		)
		(fp_line
			(start 0.7874 0.4064)
			(end -0.7874 0.4064)
			(stroke
				(width 0.1524)
				(type default)
			)
			(layer "F.SilkS")
		)
		(fp_line
			(start -0.7874 0.4064)
			(end -0.7874 -0.4064)
			(stroke
				(width 0.1524)
				(type default)
			)
			(layer "F.SilkS")
		)
		(fp_line
			(start -0.12065 -0.305054)
			(end -0.12065 -0.2794)
			(stroke
				(width 0.1)
				(type default)
			)
			(layer "F.Fab")
		)
		(fp_line
			(start -0.67945 -0.305054)
			(end -0.12065 -0.305054)
			(stroke
				(width 0.1)
				(type default)
			)
			(layer "F.Fab")
		)
		(fp_line
			(start 0.67945 -0.3048)
			(end 0.67945 0.3048)
			(stroke
				(width 0.1)
				(type default)
			)
			(layer "F.Fab")
		)
		(fp_line
			(start 0.12065 -0.3048)
			(end 0.67945 -0.3048)
			(stroke
				(width 0.1)
				(type default)
			)
			(layer "F.Fab")
		)
		(fp_line
			(start 0.12065 -0.2794)
			(end 0.12065 -0.3048)
			(stroke
				(width 0.1)
				(type default)
			)
			(layer "F.Fab")
		)
		(fp_line
			(start -0.12065 -0.2794)
			(end 0.12065 -0.2794)
			(stroke
				(width 0.1)
				(type default)
			)
			(layer "F.Fab")
		)
		(fp_line
			(start 0.120396 0.2794)
			(end -0.12065 0.2794)
			(stroke
				(width 0.1)
				(type default)
			)
			(layer "F.Fab")
		)
		(fp_line
			(start -0.12065 0.2794)
			(end -0.12065 0.3048)
			(stroke
				(width 0.1)
				(type default)
			)
			(layer "F.Fab")
		)
		(fp_line
			(start 0.67945 0.3048)
			(end 0.120396 0.3048)
			(stroke
				(width 0.1)
				(type default)
			)
			(layer "F.Fab")
		)
		(fp_line
			(start 0.120396 0.3048)
			(end 0.120396 0.2794)
			(stroke
				(width 0.1)
				(type default)
			)
			(layer "F.Fab")
		)
		(fp_line
			(start -0.12065 0.3048)
			(end -0.67945 0.3048)
			(stroke
				(width 0.1)
				(type default)
			)
			(layer "F.Fab")
		)
		(fp_line
			(start -0.67945 0.3048)
			(end -0.67945 -0.305054)
			(stroke
				(width 0.1)
				(type default)
			)
			(layer "F.Fab")
		)
		(pad "1" smd circle
			(at -0.40005 0 90)
			(size 0 0)
			(layers "F.Cu" "F.Mask" "F.Paste")
			(net "P1V8_AUX")
		)
		(pad "2" smd circle
			(at 0.40005 0 90)
			(size 0 0)
			(layers "F.Cu" "F.Mask" "F.Paste")
			(net "FAB_BMC_REV_ID2")
		)
	)
	(footprint ""
		(layer "F.Cu")
		(at 78.724506 -152.990804 90)
		(property "Reference" "PC152"
			(at 0 0 90)
			(layer "F.SilkS")
			(hide yes)
			(effects
				(font
					(size 1.27 1.27)
				)
			)
		)
		(property "Value" ""
			(at 0 0 90)
			(layer "F.Fab")
			(effects
				(font
					(size 1.27 1.27)
				)
			)
		)
		(duplicate_pad_numbers_are_jumpers no)
		(fp_line
			(start 1.524 -0.762)
			(end 1.524 0.762)
			(stroke
				(width 0.1524)
				(type default)
			)
			(layer "F.SilkS")
		)
		(fp_line
			(start -1.524 -0.762)
			(end 1.524 -0.762)
			(stroke
				(width 0.1524)
				(type default)
			)
			(layer "F.SilkS")
		)
		(fp_line
			(start 1.524 0.762)
			(end -1.524 0.762)
			(stroke
				(width 0.1524)
				(type default)
			)
			(layer "F.SilkS")
		)
		(fp_line
			(start -1.524 0.762)
			(end -1.524 -0.762)
			(stroke
				(width 0.1524)
				(type default)
			)
			(layer "F.SilkS")
		)
		(fp_line
			(start 1.1049 -0.724916)
			(end -1.1049 -0.724916)
			(stroke
				(width 0.1)
				(type default)
			)
			(layer "F.Fab")
		)
		(fp_line
			(start -1.1049 -0.724916)
			(end -1.1049 0.724916)
			(stroke
				(width 0.1)
				(type default)
			)
			(layer "F.Fab")
		)
		(fp_line
			(start 1.1049 0.724916)
			(end 1.1049 -0.724916)
			(stroke
				(width 0.1)
				(type default)
			)
			(layer "F.Fab")
		)
		(fp_line
			(start -1.1049 0.724916)
			(end 1.1049 0.724916)
			(stroke
				(width 0.1)
				(type default)
			)
			(layer "F.Fab")
		)
		(pad "1" smd rect
			(at -0.889 0 270)
			(size 1.016 1.27)
			(layers "F.Cu" "F.Mask" "F.Paste")
			(net "SW_P12V_AUX_PVDD18_S5_P1_FLT")
		)
		(pad "2" smd rect
			(at 0.889 0 270)
			(size 1.016 1.27)
			(layers "F.Cu" "F.Mask" "F.Paste")
			(net "GND")
		)
	)
	(footprint ""
		(layer "F.Cu")
		(at 382.320292 -378.95403 -90)
		(property "Reference" "C882"
			(at 0 0 270)
			(layer "F.SilkS")
			(hide yes)
			(effects
				(font
					(size 1.27 1.27)
				)
			)
		)
		(property "Value" ""
			(at 0 0 270)
			(layer "F.Fab")
			(effects
				(font
					(size 1.27 1.27)
				)
			)
		)
		(duplicate_pad_numbers_are_jumpers no)
		(fp_line
			(start -0.299974 0.150114)
			(end -0.299974 -0.150114)
			(stroke
				(width 0.1)
				(type default)
			)
			(layer "F.Fab")
		)
		(fp_line
			(start 0.299974 0.150114)
			(end -0.299974 0.150114)
			(stroke
				(width 0.1)
				(type default)
			)
			(layer "F.Fab")
		)
		(fp_line
			(start -0.299974 -0.150114)
			(end 0.299974 -0.150114)
			(stroke
				(width 0.1)
				(type default)
			)
			(layer "F.Fab")
		)
		(fp_line
			(start 0.299974 -0.150114)
			(end 0.299974 0.150114)
			(stroke
				(width 0.1)
				(type default)
			)
			(layer "F.Fab")
		)
		(pad "1" smd rect
			(at -0.2667 0 270)
			(size 0.3048 0.381)
			(layers "F.Cu" "F.Mask" "F.Paste")
			(net "P5E_CPU0_P3_TX_C_DN<9>")
		)
		(pad "2" smd rect
			(at 0.2667 0 270)
			(size 0.3048 0.381)
			(layers "F.Cu" "F.Mask" "F.Paste")
			(net "P5E_CPU0_P3_TX_DN<9>")
		)
	)
)
